FILE_TYPE=LIBRARY_PARTS;
TIME=' Created/Modified on Fri Aug 20 09:31:23 2010' ;
primitive 'SN74LVC1G07DBVR';
  pin
    'A':
      PIN_NUMBER='(2)';
      INPUT_LOAD='(-0.01,0.01)';
    'Y':
      PIN_NUMBER='(4)';
      OUTPUT_LOAD='(1.0,*)';
      OUTPUT_TYPE='(OC,AND)';
    'NC':
      PIN_NUMBER='(1)';
      INPUT_LOAD='(-0.01,0.01)';
      OUTPUT_LOAD='(1.0,-1.0)';
      OUTPUT_TYPE='(TS,TS)';
    'VCC':
      PIN_NUMBER='(5)';
      PINUSE='POWER';
    'GND':
      PIN_NUMBER='(3)';
      PINUSE='POWER';
  end_pin;
  body
    CLASS='IC';
    PART_NAME='SN74LVC1G07DBVR';
    PHYS_DES_PREFIX='U';
  end_body;
end_primitive;
END.
